# S9S_MB_2U (Grand Teton) — schematic netlist excerpt (pin names and nets, part order shuffled) for the footprints in the layout excerpt that follows; sources: Cadence DE-HDL packaged netlist, KiCad conversion of 03242023_DA0F0TMBIJ0_F0T_Motherboard_J_brd_V01_OCP.brd

J8  SCONN288_ADR50017P087CC  SCONN288_ADR50017-P087CC IO  pkg DDR288S_1-1VXB  page 89
  VIN_BULK0  = P12V_S3_AUX_CPU0_NVDIMM
  RFU0  = TP_CHD_CPU0_DIMM2_FRU_0
  VIN_MGMT  = P3V3_AUX
  HSCL  = I3C_SPD_DDRABCD_CPU0_LVC1_SCL_7
  HSDA  = I3C_SPD_DDRABCD_CPU0_LVC1_SDA
  VSS0  = GND
  DQ0_A  = M_D_CPU0_SA_DQ<0>
  VSS1  = GND
  DQ1_A  = M_D_CPU0_SA_DQ<1>
  VSS2  = GND
  DQS0_A_T  = M_D_CPU0_SA_DQS_DP<0>
  DQS0_A_C  = M_D_CPU0_SA_DQS_DN<0>
  VSS3  = GND
  DQ4_A  = M_D_CPU0_SA_DQ<4>
  VSS4  = GND
  DQ5_A  = M_D_CPU0_SA_DQ<5>
  VSS5  = GND
  DQ8_A  = M_D_CPU0_SA_DQ<8>
  VSS6  = GND
  DQ9_A  = M_D_CPU0_SA_DQ<9>
  VSS7  = GND
  DQS1_A_T  = M_D_CPU0_SA_DQS_DP<1>
  DQS1_A_C  = M_D_CPU0_SA_DQS_DN<1>
  VSS8  = GND
  DQ12_A  = M_D_CPU0_SA_DQ<12>
  VSS9  = GND
  DQ13_A  = M_D_CPU0_SA_DQ<13>
  VSS10  = GND
  DQ16_A  = M_D_CPU0_SA_DQ<16>
  VSS11  = GND
  DQ17_A  = M_D_CPU0_SA_DQ<17>
  VSS12  = GND
  DQS2_A_T  = M_D_CPU0_SA_DQS_DP<2>
  DQS2_A_C  = M_D_CPU0_SA_DQS_DN<2>
  VSS13  = GND
  DQ20_A  = M_D_CPU0_SA_DQ<20>
  VSS14  = GND
  DQ21_A  = M_D_CPU0_SA_DQ<21>
  VSS15  = GND
  DQ24_A  = M_D_CPU0_SA_DQ<24>
  VSS16  = GND
  DQ25_A  = M_D_CPU0_SA_DQ<25>
  VSS17  = GND
  DQS3_A_T  = M_D_CPU0_SA_DQS_DP<3>
  DQS3_A_C  = M_D_CPU0_SA_DQS_DN<3>
  VSS18  = GND
  DQ28_A  = M_D_CPU0_SA_DQ<28>
  VSS19  = GND
  DQ29_A  = M_D_CPU0_SA_DQ<29>
  VSS20  = GND
  CB0_A  = M_D_CPU0_SA_CB<0>
  VSS21  = GND
  CB1_A  = M_D_CPU0_SA_CB<1>
  VSS22  = GND
  DQS4_A_T  = M_D_CPU0_SA_DQS_DP<4>
  DQS4_A_C  = M_D_CPU0_SA_DQS_DN<4>
  VSS23  = GND
  CB4_A  = M_D_CPU0_SA_CB<4>
  VSS24  = GND
  CB5_A  = M_D_CPU0_SA_CB<5>
  VSS25  = GND
  ALERT_N  = M_D_CPU0_ALERT_N
  VSS26  = GND
  CS0_A_N  = M_D_CPU0_SA_CS_N<2>
  VSS27  = GND
  CA0_A  = M_D_CPU0_SA_CA<0>
  VSS28  = GND
  CA2_A  = M_D_CPU0_SA_CA<2>
  VSS29  = GND
  CA4_A  = M_D_CPU0_SA_CA<4>
  VSS30  = GND
  CA6_A  = M_D_CPU0_SA_CA<6>
  VSS31  = GND
  PAR_A  = M_D_CPU0_SA_PAR
  VSS32  = GND
  CA0_B  = M_D_CPU0_SB_CA<0>
  VSS33  = GND
  CA2_B  = M_D_CPU0_SB_CA<2>
  VSS34  = GND
  CA4_B  = M_D_CPU0_SB_CA<4>
  VSS35  = GND
  CA6_B  = M_D_CPU0_SB_CA<6>
  VSS36  = GND
  CS0_B_N  = M_D_CPU0_SB_CS_N<2>
  VSS37  = GND
  \lbd||rsp_a_n\  = M_D_CPU0_SA_RSP<1>
  \lbs||rsp_b_n\  = M_D_CPU0_SB_RSP<1>
  VSS38  = GND
  CB4_B  = M_D_CPU0_SB_CB<4>
  VSS39  = GND
  CB5_B  = M_D_CPU0_SB_CB<5>
  VSS40  = GND
  \dqs9_b_t||tdqs9_b_t||dbi4_b_n\  = M_D_CPU0_SB_DQS_DP<9>
  \dqs9_b_c||tdqs9_b_c\  = M_D_CPU0_SB_DQS_DN<9>
  VSS41  = GND
  CB0_B  = M_D_CPU0_SB_CB<0>
  VSS42  = GND
  CB1_B  = M_D_CPU0_SB_CB<1>
  VSS43  = GND
  DQ0_B  = M_D_CPU0_SB_DQ<0>
  VSS44  = GND
  DQ1_B  = M_D_CPU0_SB_DQ<1>
  VSS45  = GND
  DQS0_B_T  = M_D_CPU0_SB_DQS_DP<0>
  DQS0_B_C  = M_D_CPU0_SB_DQS_DN<0>
  VSS46  = GND
  DQ4_B  = M_D_CPU0_SB_DQ<4>
  VSS47  = GND
  DQ5_B  = M_D_CPU0_SB_DQ<5>
  VSS48  = GND
  DQ8_B  = M_D_CPU0_SB_DQ<8>
  VSS49  = GND
  DQ9_B  = M_D_CPU0_SB_DQ<9>
  VSS50  = GND
  DQS1_B_T  = M_D_CPU0_SB_DQS_DP<1>
  DQS1_B_C  = M_D_CPU0_SB_DQS_DN<1>
  VSS51  = GND
  DQ12_B  = M_D_CPU0_SB_DQ<12>
  VSS52  = GND
  DQ13_B  = M_D_CPU0_SB_DQ<13>
  VSS53  = GND
  DQ16_B  = M_D_CPU0_SB_DQ<16>
  VSS54  = GND
  DQ17_B  = M_D_CPU0_SB_DQ<17>
  VSS55  = GND
  DQS2_B_T  = M_D_CPU0_SB_DQS_DP<2>
  DQS2_B_C  = M_D_CPU0_SB_DQS_DN<2>
  VSS56  = GND
  DQ20_B  = M_D_CPU0_SB_DQ<20>
  VSS57  = GND
  DQ21_B  = M_D_CPU0_SB_DQ<21>
  VSS58  = GND
  DQ24_B  = M_D_CPU0_SB_DQ<24>
  VSS59  = GND
  DQ25_B  = M_D_CPU0_SB_DQ<25>
  VSS60  = GND
  DQS3_B_T  = M_D_CPU0_SB_DQS_DP<3>
  DQS3_B_C  = M_D_CPU0_SB_DQS_DN<3>
  VSS61  = GND
  DQ28_B  = M_D_CPU0_SB_DQ<28>
  VSS62  = GND
  DQ29_B  = M_D_CPU0_SB_DQ<29>
  VSS63  = GND
  RFU1  = TP_CHD_CPU0_DIMM2_FRU_1
  VIN_BULK1  = P12V_S3_AUX_CPU0_NVDIMM
  VIN_BULK2  = P12V_S3_AUX_CPU0_NVDIMM
  \pwr_good||fail_n\  = PWRGD_CHD_CPU0_DIMM2
  HSA  = PD_CHD_CPU0_DIMM2_SAA
  RFU2  = TP_CHD_CPU0_DIMM2_FRU_2
  RFU3  = TP_CHD_CPU0_DIMM2_FRU_3
  VSS64  = GND
  DQ2_A  = M_D_CPU0_SA_DQ<2>
  VSS65  = GND
  DQ3_A  = M_D_CPU0_SA_DQ<3>
  VSS66  = GND
  \dqs5_a_c||tdqs5_a_c||dqs5_a_t||tdqs5_a_t\  = M_D_CPU0_SA_DQS_DN<5>
  \dqs5_a_t||tdqs5_a_t\  = M_D_CPU0_SA_DQS_DP<5>
  VSS67  = GND
  DQ6_A  = M_D_CPU0_SA_DQ<6>
  VSS68  = GND
  DQ7_A  = M_D_CPU0_SA_DQ<7>
  VSS69  = GND
  DQ10_A  = M_D_CPU0_SA_DQ<10>
  VSS70  = GND
  DQ11_A  = M_D_CPU0_SA_DQ<11>
  VSS71  = GND
  \dqs6_a_c||tdqs6_a_c||dqs6_a_t||tdqs6_a_t\  = M_D_CPU0_SA_DQS_DN<6>
  \dqs6_a_t||tdqs6_a_t\  = M_D_CPU0_SA_DQS_DP<6>
  VSS72  = GND
  DQ14_A  = M_D_CPU0_SA_DQ<14>
  VSS73  = GND
  DQ15_A  = M_D_CPU0_SA_DQ<15>
  VSS74  = GND
  DQ18_A  = M_D_CPU0_SA_DQ<18>
  VSS75  = GND
  DQ19_A  = M_D_CPU0_SA_DQ<19>
  VSS76  = GND
  \dqs7_a_c||tdqs7_a_c\  = M_D_CPU0_SA_DQS_DN<7>
  \dqs7_a_t||tdqs7_a_t\  = M_D_CPU0_SA_DQS_DP<7>
  VSS77  = GND
  DQ22_A  = M_D_CPU0_SA_DQ<22>
  VSS78  = GND
  DQ23_A  = M_D_CPU0_SA_DQ<23>
  VSS79  = GND
  DQ26_A  = M_D_CPU0_SA_DQ<26>
  VSS80  = GND
  DQ27_A  = M_D_CPU0_SA_DQ<27>
  VSS81  = GND
  \dqs8_a_c||tdqs8_a_c\  = M_D_CPU0_SA_DQS_DN<8>
  \dqs8_a_t||tdqs8_a_t\  = M_D_CPU0_SA_DQS_DP<8>
  VSS82  = GND
  DQ30_A  = M_D_CPU0_SA_DQ<30>
  VSS83  = GND
  DQ31_A  = M_D_CPU0_SA_DQ<31>
  VSS84  = GND
  CB2_A  = M_D_CPU0_SA_CB<2>
  VSS85  = GND
  CB3_A  = M_D_CPU0_SA_CB<3>
  VSS86  = GND
  \dqs9_a_c||tdqs9_a_c\  = M_D_CPU0_SA_DQS_DN<9>
  \dqs9_a_t||tdqs9_a_t\  = M_D_CPU0_SA_DQS_DP<9>
  VSS87  = GND
  CB6_A  = M_D_CPU0_SA_CB<6>
  VSS88  = GND
  CB7_A  = M_D_CPU0_SA_CB<7>
  VSS89  = GND
  RESET_N  = RST_M_CD_CPU0_FPGA_N
  VSS90  = GND
  CS1_A_N  = M_D_CPU0_SA_CS_N<3>
  VSS91  = GND
  CA1_A  = M_D_CPU0_SA_CA<1>
  VSS92  = GND
  CA3_A  = M_D_CPU0_SA_CA<3>
  VSS93  = GND
  CA5_A  = M_D_CPU0_SA_CA<5>
  VSS94  = GND
  CK_T  = M_D_CPU0_CLK_DP<1>
  CK_C  = M_D_CPU0_CLK_DN<1>
  VSS95  = GND
  RFU4  = TP_CHD_CPU0_DIMM2_FRU_4
  CA1_B  = M_D_CPU0_SB_CA<1>
  VSS96  = GND
  CA3_B  = M_D_CPU0_SB_CA<3>
  VSS97  = GND
  CA5_B  = M_D_CPU0_SB_CA<5>
  VSS98  = GND
  PAR_B  = M_D_CPU0_SB_PAR
  VSS99  = GND
  CS1_B_N  = M_D_CPU0_SB_CS_N<3>
  VSS100  = GND
  RFU5  = TP_CHD_CPU0_DIMM2_FRU_5
  RFU6  = TP_CHD_CPU0_DIMM2_FRU_6
  VSS101  = GND
  CB6_B  = M_D_CPU0_SB_CB<6>
  VSS102  = GND
  CB7_B  = M_D_CPU0_SB_CB<7>
  VSS103  = GND
  DQS4_B_C  = M_D_CPU0_SB_DQS_DN<4>
  DQS4_B_T  = M_D_CPU0_SB_DQS_DP<4>
  VSS104  = GND
  CB2_B  = M_D_CPU0_SB_CB<2>
  VSS105  = GND
  CB3_B  = M_D_CPU0_SB_CB<3>
  VSS106  = GND
  DQ2_B  = M_D_CPU0_SB_DQ<2>
  VSS107  = GND
  DQ3_B  = M_D_CPU0_SB_DQ<3>
  VSS108  = GND
  \dqs5_b_c||tdqs5_b_c\  = M_D_CPU0_SB_DQS_DN<5>
  \dqs5_b_t||tdqs5_b_t\  = M_D_CPU0_SB_DQS_DP<5>
  VSS109  = GND
  DQ6_B  = M_D_CPU0_SB_DQ<6>
  VSS110  = GND
  DQ7_B  = M_D_CPU0_SB_DQ<7>
  VSS111  = GND
  DQ10_B  = M_D_CPU0_SB_DQ<10>
  VSS112  = GND
  DQ11_B  = M_D_CPU0_SB_DQ<11>
  VSS113  = GND
  \dqs6_b_c||tdqs6_b_c\  = M_D_CPU0_SB_DQS_DN<6>
  \dqs6_b_t||tdqs6_b_t\  = M_D_CPU0_SB_DQS_DP<6>
  VSS114  = GND
  DQ14_B  = M_D_CPU0_SB_DQ<14>
  VSS115  = GND
  DQ15_B  = M_D_CPU0_SB_DQ<15>
  VSS116  = GND
  DQ18_B  = M_D_CPU0_SB_DQ<18>
  VSS117  = GND
  DQ19_B  = M_D_CPU0_SB_DQ<19>
  VSS118  = GND
  \dqs7_b_c||tdqs7_b_c\  = M_D_CPU0_SB_DQS_DN<7>
  \dqs7_b_t||tdqs7_b_t\  = M_D_CPU0_SB_DQS_DP<7>
  VSS119  = GND
  DQ22_B  = M_D_CPU0_SB_DQ<22>
  VSS120  = GND
  DQ23_B  = M_D_CPU0_SB_DQ<23>
  VSS121  = GND
  DQ26_B  = M_D_CPU0_SB_DQ<26>
  VSS122  = GND
  DQ27_B  = M_D_CPU0_SB_DQ<27>
  VSS123  = GND
  \dqs8_b_c||tdqs8_b_c\  = M_D_CPU0_SB_DQS_DN<8>
  \dqs8_b_t||tdqs8_b_t\  = M_D_CPU0_SB_DQS_DP<8>
  VSS124  = GND
  DQ30_B  = M_D_CPU0_SB_DQ<30>
  VSS125  = GND
  DQ31_B  = M_D_CPU0_SB_DQ<31>
  VSS126  = GND
  G1  = GND
  G2  = GND
  G3  = GND

(kicad_pcb
	(version 20260206)
	(generator "pcbnew")
	(generator_version "10.0")
	(general
		(thickness 1.6)
		(legacy_teardrops no)
	)
	(paper "A4")
	(title_block
		(title "03242023_DA0F0TMBIJ0_F0T_Motherboard_J_brd_V01_OCP.brd")
		(comment 1 "Grand Teton / footprint 652 of 6105 (J8), pads 183-228 of 291")
	)
	(layers
		(0 "F.Cu" signal "TOP")
		(4 "In1.Cu" signal "GND")
		(6 "In2.Cu" signal "IN1")
		(8 "In3.Cu" signal "GND1")
		(10 "In4.Cu" signal "IN2")
		(12 "In5.Cu" signal "GND2")
		(14 "In6.Cu" signal "IN3")
		(16 "In7.Cu" signal "GND3")
		(18 "In8.Cu" signal "VCC")
		(20 "In9.Cu" signal "VCC1")
		(22 "In10.Cu" signal "GND4")
		(24 "In11.Cu" signal "IN4")
		(26 "In12.Cu" signal "GND5")
		(28 "In13.Cu" signal "IN5")
		(30 "In14.Cu" signal "GND6")
		(32 "In15.Cu" signal "IN6")
		(34 "In16.Cu" signal "GND7")
		(2 "B.Cu" signal "BOTTOM")
		(9 "F.Adhes" user "F.Adhesive")
		(11 "B.Adhes" user "B.Adhesive")
		(13 "F.Paste" user "Package Geometry/Pastemask Top")
		(15 "B.Paste" user "Package Geometry/Pastemask Bottom")
		(5 "F.SilkS" user "Ref Des/Silkscreen Top")
		(7 "B.SilkS" user "Ref Des/Silkscreen Bottom")
		(1 "F.Mask" user "Board Geometry/Soldermask Top")
		(3 "B.Mask" user "Board Geometry/Soldermask Bottom")
		(17 "Dwgs.User" user "User.Drawings")
		(19 "Cmts.User" user "User.Comments")
		(21 "Eco1.User" user "User.Eco1")
		(23 "Eco2.User" user "User.Eco2")
		(25 "Edge.Cuts" user "Board Geometry/Outline")
		(27 "Margin" user)
		(31 "F.CrtYd" user "Package Geometry/Place Bound Top")
		(29 "B.CrtYd" user "Package Geometry/Place Bound Bottom")
		(35 "F.Fab" user "Ref Des/Assembly Top")
		(33 "B.Fab" user "Ref Des/Assembly Bottom")
	)
	(footprint ""
		(layer "F.Cu")
		(at 265.674348 -258.091686)
		(property "Reference" "J8"
			(at -3.683 -81.702148 0)
			(unlocked yes)
			(layer "F.SilkS")
			(effects
				(font
					(size 0.7874 0.5842)
					(thickness 0.1524)
				)
				(justify left)
			)
		)
		(property "Value" ""
			(at 0 0 0)
			(layer "F.Fab")
			(effects
				(font
					(size 1.27 1.27)
				)
			)
		)
		(duplicate_pad_numbers_are_jumpers no)
		(pad "183" smd rect
			(at 2.050034 -31.025084 270)
			(size 0.519938 1.4986)
			(layers "F.Cu" "F.Mask" "F.Paste")
			(net "M_D_CPU0_SA_DQ<23>")
		)
		(pad "184" smd rect
			(at 2.050034 -30.174946 270)
			(size 0.519938 1.4986)
			(layers "F.Cu" "F.Mask" "F.Paste")
			(net "GND")
		)
		(pad "185" smd rect
			(at 2.050034 -29.325062 270)
			(size 0.519938 1.4986)
			(layers "F.Cu" "F.Mask" "F.Paste")
			(net "M_D_CPU0_SA_DQ<26>")
		)
		(pad "186" smd rect
			(at 2.050034 -28.474924 270)
			(size 0.519938 1.4986)
			(layers "F.Cu" "F.Mask" "F.Paste")
			(net "GND")
		)
		(pad "187" smd rect
			(at 2.050034 -27.62504 270)
			(size 0.519938 1.4986)
			(layers "F.Cu" "F.Mask" "F.Paste")
			(net "M_D_CPU0_SA_DQ<27>")
		)
		(pad "188" smd rect
			(at 2.050034 -26.774902 270)
			(size 0.519938 1.4986)
			(layers "F.Cu" "F.Mask" "F.Paste")
			(net "GND")
		)
		(pad "189" smd rect
			(at 2.050034 -25.925018 270)
			(size 0.519938 1.4986)
			(layers "F.Cu" "F.Mask" "F.Paste")
			(net "M_D_CPU0_SA_DQS_DN<8>")
		)
		(pad "190" smd rect
			(at 2.050034 -25.07488 270)
			(size 0.519938 1.4986)
			(layers "F.Cu" "F.Mask" "F.Paste")
			(net "M_D_CPU0_SA_DQS_DP<8>")
		)
		(pad "191" smd rect
			(at 2.050034 -24.224996 270)
			(size 0.519938 1.4986)
			(layers "F.Cu" "F.Mask" "F.Paste")
			(net "GND")
		)
		(pad "192" smd rect
			(at 2.050034 -23.375112 270)
			(size 0.519938 1.4986)
			(layers "F.Cu" "F.Mask" "F.Paste")
			(net "M_D_CPU0_SA_DQ<30>")
		)
		(pad "193" smd rect
			(at 2.050034 -22.524974 270)
			(size 0.519938 1.4986)
			(layers "F.Cu" "F.Mask" "F.Paste")
			(net "GND")
		)
		(pad "194" smd rect
			(at 2.050034 -21.67509 270)
			(size 0.519938 1.4986)
			(layers "F.Cu" "F.Mask" "F.Paste")
			(net "M_D_CPU0_SA_DQ<31>")
		)
		(pad "195" smd rect
			(at 2.050034 -20.824952 270)
			(size 0.519938 1.4986)
			(layers "F.Cu" "F.Mask" "F.Paste")
			(net "GND")
		)
		(pad "196" smd rect
			(at 2.050034 -19.975068 270)
			(size 0.519938 1.4986)
			(layers "F.Cu" "F.Mask" "F.Paste")
			(net "M_D_CPU0_SA_CB<2>")
		)
		(pad "197" smd rect
			(at 2.050034 -19.12493 270)
			(size 0.519938 1.4986)
			(layers "F.Cu" "F.Mask" "F.Paste")
			(net "GND")
		)
		(pad "198" smd rect
			(at 2.050034 -18.275046 270)
			(size 0.519938 1.4986)
			(layers "F.Cu" "F.Mask" "F.Paste")
			(net "M_D_CPU0_SA_CB<3>")
		)
		(pad "199" smd rect
			(at 2.050034 -17.424908 270)
			(size 0.519938 1.4986)
			(layers "F.Cu" "F.Mask" "F.Paste")
			(net "GND")
		)
		(pad "200" smd rect
			(at 2.050034 -16.575024 270)
			(size 0.519938 1.4986)
			(layers "F.Cu" "F.Mask" "F.Paste")
			(net "M_D_CPU0_SA_DQS_DN<9>")
		)
		(pad "201" smd rect
			(at 2.050034 -15.724886 270)
			(size 0.519938 1.4986)
			(layers "F.Cu" "F.Mask" "F.Paste")
			(net "M_D_CPU0_SA_DQS_DP<9>")
		)
		(pad "202" smd rect
			(at 2.050034 -14.875002 270)
			(size 0.519938 1.4986)
			(layers "F.Cu" "F.Mask" "F.Paste")
			(net "GND")
		)
		(pad "203" smd rect
			(at 2.050034 -14.025118 270)
			(size 0.519938 1.4986)
			(layers "F.Cu" "F.Mask" "F.Paste")
			(net "M_D_CPU0_SA_CB<6>")
		)
		(pad "204" smd rect
			(at 2.050034 -13.17498 270)
			(size 0.519938 1.4986)
			(layers "F.Cu" "F.Mask" "F.Paste")
			(net "GND")
		)
		(pad "205" smd rect
			(at 2.050034 -12.325096 270)
			(size 0.519938 1.4986)
			(layers "F.Cu" "F.Mask" "F.Paste")
			(net "M_D_CPU0_SA_CB<7>")
		)
		(pad "206" smd rect
			(at 2.050034 -11.474958 270)
			(size 0.519938 1.4986)
			(layers "F.Cu" "F.Mask" "F.Paste")
			(net "GND")
		)
		(pad "207" smd rect
			(at 2.050034 -10.625074 270)
			(size 0.519938 1.4986)
			(layers "F.Cu" "F.Mask" "F.Paste")
			(net "RST_M_CD_CPU0_FPGA_N")
		)
		(pad "208" smd rect
			(at 2.050034 -9.774936 270)
			(size 0.519938 1.4986)
			(layers "F.Cu" "F.Mask" "F.Paste")
			(net "GND")
		)
		(pad "209" smd rect
			(at 2.050034 -8.925052 270)
			(size 0.519938 1.4986)
			(layers "F.Cu" "F.Mask" "F.Paste")
			(net "M_D_CPU0_SA_CS_N<3>")
		)
		(pad "210" smd rect
			(at 2.050034 -8.074914 270)
			(size 0.519938 1.4986)
			(layers "F.Cu" "F.Mask" "F.Paste")
			(net "GND")
		)
		(pad "211" smd rect
			(at 2.050034 -7.22503 270)
			(size 0.519938 1.4986)
			(layers "F.Cu" "F.Mask" "F.Paste")
			(net "M_D_CPU0_SA_CA<1>")
		)
		(pad "212" smd rect
			(at 2.050034 -6.374892 270)
			(size 0.519938 1.4986)
			(layers "F.Cu" "F.Mask" "F.Paste")
			(net "GND")
		)
		(pad "213" smd rect
			(at 2.050034 -5.525008 270)
			(size 0.519938 1.4986)
			(layers "F.Cu" "F.Mask" "F.Paste")
			(net "M_D_CPU0_SA_CA<3>")
		)
		(pad "214" smd rect
			(at 2.050034 -4.675124 270)
			(size 0.519938 1.4986)
			(layers "F.Cu" "F.Mask" "F.Paste")
			(net "GND")
		)
		(pad "215" smd rect
			(at 2.050034 -3.824986 270)
			(size 0.519938 1.4986)
			(layers "F.Cu" "F.Mask" "F.Paste")
			(net "M_D_CPU0_SA_CA<5>")
		)
		(pad "216" smd rect
			(at 2.050034 -2.975102 270)
			(size 0.519938 1.4986)
			(layers "F.Cu" "F.Mask" "F.Paste")
			(net "GND")
		)
		(pad "217" smd rect
			(at 2.050034 -2.124964 270)
			(size 0.519938 1.4986)
			(layers "F.Cu" "F.Mask" "F.Paste")
			(net "M_D_CPU0_CLK_DP<1>")
		)
		(pad "218" smd rect
			(at 2.050034 -1.27508 270)
			(size 0.519938 1.4986)
			(layers "F.Cu" "F.Mask" "F.Paste")
			(net "M_D_CPU0_CLK_DN<1>")
		)
		(pad "219" smd rect
			(at 2.050034 -0.424942 270)
			(size 0.519938 1.4986)
			(layers "F.Cu" "F.Mask" "F.Paste")
			(net "GND")
		)
		(pad "220" smd rect
			(at 2.050034 5.525008 270)
			(size 0.519938 1.4986)
			(layers "F.Cu" "F.Mask" "F.Paste")
			(net "TP_CHD_CPU0_DIMM2_FRU_4")
		)
		(pad "221" smd rect
			(at 2.050034 6.374892 270)
			(size 0.519938 1.4986)
			(layers "F.Cu" "F.Mask" "F.Paste")
			(net "M_D_CPU0_SB_CA<1>")
		)
		(pad "222" smd rect
			(at 2.050034 7.22503 270)
			(size 0.519938 1.4986)
			(layers "F.Cu" "F.Mask" "F.Paste")
			(net "GND")
		)
		(pad "223" smd rect
			(at 2.050034 8.074914 270)
			(size 0.519938 1.4986)
			(layers "F.Cu" "F.Mask" "F.Paste")
			(net "M_D_CPU0_SB_CA<3>")
		)
		(pad "224" smd rect
			(at 2.050034 8.925052 270)
			(size 0.519938 1.4986)
			(layers "F.Cu" "F.Mask" "F.Paste")
			(net "GND")
		)
		(pad "225" smd rect
			(at 2.050034 9.774936 270)
			(size 0.519938 1.4986)
			(layers "F.Cu" "F.Mask" "F.Paste")
			(net "M_D_CPU0_SB_CA<5>")
		)
		(pad "226" smd rect
			(at 2.050034 10.625074 270)
			(size 0.519938 1.4986)
			(layers "F.Cu" "F.Mask" "F.Paste")
			(net "GND")
		)
		(pad "227" smd rect
			(at 2.050034 11.474958 270)
			(size 0.519938 1.4986)
			(layers "F.Cu" "F.Mask" "F.Paste")
			(net "M_D_CPU0_SB_PAR")
		)
		(pad "228" smd rect
			(at 2.050034 12.325096 270)
			(size 0.519938 1.4986)
			(layers "F.Cu" "F.Mask" "F.Paste")
			(net "GND")
		)
	)
)
